#ISCELL
  mstr_misc dns *
  *
#ISCELL
  mstr_symbols intel_corp_bpage *
  *
#CELL
  mstr_discrete res *
  page164_i11
#ISCELL
  mstr_symbols p3v3_stby *
  page164_i12
#CELL
  mstr_discrete res *
  page164_i13
#CELL
  mstr_discrete res *
  page164_i14
#ISCELL
  mstr_standard offpage *
  page164_i15
#ISCELL
  mstr_standard offpage *
  page164_i16
#ISCELL
  mstr_standard offpage *
  page164_i17
#ISCELL
  mstr_standard offpage *
  page164_i18
#CELL
  mstr_discrete res *
  page164_i19
#ISCELL
  mstr_standard offpage *
  page164_i2
#CELL
  mstr_discrete res *
  page164_i20
#CELL
  mstr_discrete res *
  page164_i21
#CELL
  mstr_discrete res *
  page164_i22
#CELL
  mstr_discrete res *
  page164_i24
#CELL
  mstr_discrete res *
  page164_i25
#ISCELL
  mstr_symbols p3v3_stby *
  page164_i26
#CELL
  mstr_discrete res *
  page164_i27
#CELL
  mstr_discrete res *
  page164_i28
#CELL
  mstr_discrete res *
  page164_i29
#ISCELL
  mstr_standard offpage *
  page164_i3
#ISCELL
  mstr_standard offpage *
  page164_i30
#ISCELL
  mstr_symbols gnd *
  page164_i31
#CELL
  mstr_discrete res *
  page164_i32
#ISCELL
  mstr_standard offpage *
  page164_i4
#CELL
  mstr_discrete res *
  page164_i5
#CELL
  mstr_discrete res *
  page164_i6
#CELL
  mstr_discrete res *
  page164_i7
#ISCELL
  mstr_symbols gnd *
  page164_i9
